# S9S_MB_2U (Grand Teton) — schematic netlist excerpt (pin names and nets, part order shuffled) for the footprints in the layout excerpt that follows; sources: Cadence DE-HDL packaged netlist, KiCad conversion of 03242023_DA0F0TMBIJ0_F0T_Motherboard_J_brd_V01_OCP.brd

C241  Q_CAP  10UF 6.3V 20% X6S  pkg C0402  page 77 : A = PVCCIN_CPU1 ; B = GND
R4530  Q_RES  33.2 1% CHIP  pkg 0402LF  page 241 : A = SMB_SML1_PMBUS_HSC_SCL_R3 ; B = SMB_SML1_PMBUS_HSC_SCL

(kicad_pcb
	(version 20260206)
	(generator "pcbnew")
	(generator_version "10.0")
	(general
		(thickness 1.6)
		(legacy_teardrops no)
	)
	(paper "A4")
	(title_block
		(title "03242023_DA0F0TMBIJ0_F0T_Motherboard_J_brd_V01_OCP.brd")
		(comment 1 "Grand Teton / footprints 2231-2232 of 6105")
	)
	(layers
		(0 "F.Cu" signal "TOP")
		(4 "In1.Cu" signal "GND")
		(6 "In2.Cu" signal "IN1")
		(8 "In3.Cu" signal "GND1")
		(10 "In4.Cu" signal "IN2")
		(12 "In5.Cu" signal "GND2")
		(14 "In6.Cu" signal "IN3")
		(16 "In7.Cu" signal "GND3")
		(18 "In8.Cu" signal "VCC")
		(20 "In9.Cu" signal "VCC1")
		(22 "In10.Cu" signal "GND4")
		(24 "In11.Cu" signal "IN4")
		(26 "In12.Cu" signal "GND5")
		(28 "In13.Cu" signal "IN5")
		(30 "In14.Cu" signal "GND6")
		(32 "In15.Cu" signal "IN6")
		(34 "In16.Cu" signal "GND7")
		(2 "B.Cu" signal "BOTTOM")
		(9 "F.Adhes" user "F.Adhesive")
		(11 "B.Adhes" user "B.Adhesive")
		(13 "F.Paste" user "Package Geometry/Pastemask Top")
		(15 "B.Paste" user "Package Geometry/Pastemask Bottom")
		(5 "F.SilkS" user "Ref Des/Silkscreen Top")
		(7 "B.SilkS" user "Ref Des/Silkscreen Bottom")
		(1 "F.Mask" user "Board Geometry/Soldermask Top")
		(3 "B.Mask" user "Board Geometry/Soldermask Bottom")
		(17 "Dwgs.User" user "User.Drawings")
		(19 "Cmts.User" user "User.Comments")
		(21 "Eco1.User" user "User.Eco1")
		(23 "Eco2.User" user "User.Eco2")
		(25 "Edge.Cuts" user "Board Geometry/Outline")
		(27 "Margin" user)
		(31 "F.CrtYd" user "Package Geometry/Place Bound Top")
		(29 "B.CrtYd" user "Package Geometry/Place Bound Bottom")
		(35 "F.Fab" user "Ref Des/Assembly Top")
		(33 "B.Fab" user "Ref Des/Assembly Bottom")
	)
	(footprint ""
		(layer "F.Cu")
		(at 104.352852 -255.0541 90)
		(property "Reference" "C241"
			(at 0 0 90)
			(layer "F.SilkS")
			(hide yes)
			(effects
				(font
					(size 1.27 1.27)
				)
			)
		)
		(property "Value" ""
			(at 0 0 90)
			(layer "F.Fab")
			(effects
				(font
					(size 1.27 1.27)
				)
			)
		)
		(duplicate_pad_numbers_are_jumpers no)
		(fp_line
			(start 0.7874 -0.4064)
			(end 0.7874 0.4064)
			(stroke
				(width 0.1524)
				(type default)
			)
			(layer "F.SilkS")
		)
		(fp_line
			(start -0.7874 -0.4064)
			(end 0.7874 -0.4064)
			(stroke
				(width 0.1524)
				(type default)
			)
			(layer "F.SilkS")
		)
		(fp_line
			(start 0.7874 0.4064)
			(end -0.7874 0.4064)
			(stroke
				(width 0.1524)
				(type default)
			)
			(layer "F.SilkS")
		)
		(fp_line
			(start -0.7874 0.4064)
			(end -0.7874 -0.4064)
			(stroke
				(width 0.1524)
				(type default)
			)
			(layer "F.SilkS")
		)
		(fp_line
			(start -0.12065 -0.305054)
			(end -0.12065 -0.2794)
			(stroke
				(width 0.1)
				(type default)
			)
			(layer "F.Fab")
		)
		(fp_line
			(start -0.67945 -0.305054)
			(end -0.12065 -0.305054)
			(stroke
				(width 0.1)
				(type default)
			)
			(layer "F.Fab")
		)
		(fp_line
			(start 0.67945 -0.3048)
			(end 0.67945 0.3048)
			(stroke
				(width 0.1)
				(type default)
			)
			(layer "F.Fab")
		)
		(fp_line
			(start 0.12065 -0.3048)
			(end 0.67945 -0.3048)
			(stroke
				(width 0.1)
				(type default)
			)
			(layer "F.Fab")
		)
		(fp_line
			(start 0.12065 -0.2794)
			(end 0.12065 -0.3048)
			(stroke
				(width 0.1)
				(type default)
			)
			(layer "F.Fab")
		)
		(fp_line
			(start -0.12065 -0.2794)
			(end 0.12065 -0.2794)
			(stroke
				(width 0.1)
				(type default)
			)
			(layer "F.Fab")
		)
		(fp_line
			(start 0.120396 0.2794)
			(end -0.12065 0.2794)
			(stroke
				(width 0.1)
				(type default)
			)
			(layer "F.Fab")
		)
		(fp_line
			(start -0.12065 0.2794)
			(end -0.12065 0.3048)
			(stroke
				(width 0.1)
				(type default)
			)
			(layer "F.Fab")
		)
		(fp_line
			(start 0.67945 0.3048)
			(end 0.120396 0.3048)
			(stroke
				(width 0.1)
				(type default)
			)
			(layer "F.Fab")
		)
		(fp_line
			(start 0.120396 0.3048)
			(end 0.120396 0.2794)
			(stroke
				(width 0.1)
				(type default)
			)
			(layer "F.Fab")
		)
		(fp_line
			(start -0.12065 0.3048)
			(end -0.67945 0.3048)
			(stroke
				(width 0.1)
				(type default)
			)
			(layer "F.Fab")
		)
		(fp_line
			(start -0.67945 0.3048)
			(end -0.67945 -0.305054)
			(stroke
				(width 0.1)
				(type default)
			)
			(layer "F.Fab")
		)
		(pad "1" smd circle
			(at -0.40005 0 90)
			(size 0 0)
			(layers "F.Cu" "F.Mask" "F.Paste")
			(net "PVCCIN_CPU1")
		)
		(pad "2" smd circle
			(at 0.40005 0 90)
			(size 0 0)
			(layers "F.Cu" "F.Mask" "F.Paste")
			(net "GND")
		)
	)
	(footprint ""
		(layer "F.Cu")
		(at 179.09032 -409.199588)
		(property "Reference" "R4530"
			(at 0 0 0)
			(layer "F.SilkS")
			(hide yes)
			(effects
				(font
					(size 1.27 1.27)
				)
			)
		)
		(property "Value" ""
			(at 0 0 0)
			(layer "F.Fab")
			(effects
				(font
					(size 1.27 1.27)
				)
			)
		)
		(duplicate_pad_numbers_are_jumpers no)
		(fp_line
			(start -0.7874 -0.4064)
			(end 0.7874 -0.4064)
			(stroke
				(width 0.1524)
				(type default)
			)
			(layer "F.SilkS")
		)
		(fp_line
			(start -0.7874 0.4064)
			(end -0.7874 -0.4064)
			(stroke
				(width 0.1524)
				(type default)
			)
			(layer "F.SilkS")
		)
		(fp_line
			(start 0.7874 -0.4064)
			(end 0.7874 0.4064)
			(stroke
				(width 0.1524)
				(type default)
			)
			(layer "F.SilkS")
		)
		(fp_line
			(start 0.7874 0.4064)
			(end -0.7874 0.4064)
			(stroke
				(width 0.1524)
				(type default)
			)
			(layer "F.SilkS")
		)
		(fp_line
			(start -0.67945 -0.305054)
			(end -0.12065 -0.305054)
			(stroke
				(width 0.1)
				(type default)
			)
			(layer "F.Fab")
		)
		(fp_line
			(start -0.67945 0.3048)
			(end -0.67945 -0.305054)
			(stroke
				(width 0.1)
				(type default)
			)
			(layer "F.Fab")
		)
		(fp_line
			(start -0.12065 -0.305054)
			(end -0.12065 -0.2794)
			(stroke
				(width 0.1)
				(type default)
			)
			(layer "F.Fab")
		)
		(fp_line
			(start -0.12065 -0.2794)
			(end 0.12065 -0.2794)
			(stroke
				(width 0.1)
				(type default)
			)
			(layer "F.Fab")
		)
		(fp_line
			(start -0.12065 0.2794)
			(end -0.12065 0.3048)
			(stroke
				(width 0.1)
				(type default)
			)
			(layer "F.Fab")
		)
		(fp_line
			(start -0.12065 0.3048)
			(end -0.67945 0.3048)
			(stroke
				(width 0.1)
				(type default)
			)
			(layer "F.Fab")
		)
		(fp_line
			(start 0.120396 0.2794)
			(end -0.12065 0.2794)
			(stroke
				(width 0.1)
				(type default)
			)
			(layer "F.Fab")
		)
		(fp_line
			(start 0.120396 0.3048)
			(end 0.120396 0.2794)
			(stroke
				(width 0.1)
				(type default)
			)
			(layer "F.Fab")
		)
		(fp_line
			(start 0.12065 -0.3048)
			(end 0.67945 -0.3048)
			(stroke
				(width 0.1)
				(type default)
			)
			(layer "F.Fab")
		)
		(fp_line
			(start 0.12065 -0.2794)
			(end 0.12065 -0.3048)
			(stroke
				(width 0.1)
				(type default)
			)
			(layer "F.Fab")
		)
		(fp_line
			(start 0.67945 -0.3048)
			(end 0.67945 0.3048)
			(stroke
				(width 0.1)
				(type default)
			)
			(layer "F.Fab")
		)
		(fp_line
			(start 0.67945 0.3048)
			(end 0.120396 0.3048)
			(stroke
				(width 0.1)
				(type default)
			)
			(layer "F.Fab")
		)
		(pad "1" smd circle
			(at -0.40005 0)
			(size 0 0)
			(layers "F.Cu" "F.Mask" "F.Paste")
			(net "SMB_SML1_PMBUS_HSC_SCL_R3")
		)
		(pad "2" smd circle
			(at 0.40005 0)
			(size 0 0)
			(layers "F.Cu" "F.Mask" "F.Paste")
			(net "SMB_SML1_PMBUS_HSC_SCL")
		)
	)
)
